# T6G (Grand Teton) — schematic netlist excerpt (pin names and nets, part order shuffled) for the footprints in the layout excerpt that follows; sources: Cadence DE-HDL packaged netlist, KiCad conversion of 04192023_DAF0TMB3IC0_F0TG_MB_C_brd_V02_OCP.brd

C1209  Q_CAP  100PF 50V 5% NPO  pkg 0402  page 85 : A = SCM_SYS_PWROK_R2 ; B = GND
C2532  Q_CAP  22UF 4V 20% X6S  pkg C0402  page 70 : A = PVDDCR_SOC_P0 ; B = GND

(kicad_pcb
	(version 20260206)
	(generator "pcbnew")
	(generator_version "10.0")
	(general
		(thickness 1.6)
		(legacy_teardrops no)
	)
	(paper "A4")
	(title_block
		(title "04192023_DAF0TMB3IC0_F0TG_MB_C_brd_V02_OCP.brd")
		(comment 1 "Grand Teton / footprints 8150-8151 of 8354")
	)
	(layers
		(0 "F.Cu" signal "TOP")
		(4 "In1.Cu" signal "GND")
		(6 "In2.Cu" signal "IN1")
		(8 "In3.Cu" signal "GND1")
		(10 "In4.Cu" signal "IN2")
		(12 "In5.Cu" signal "GND2")
		(14 "In6.Cu" signal "IN3")
		(16 "In7.Cu" signal "GND3")
		(18 "In8.Cu" signal "VCC")
		(20 "In9.Cu" signal "VCC1")
		(22 "In10.Cu" signal "GND4")
		(24 "In11.Cu" signal "IN4")
		(26 "In12.Cu" signal "GND5")
		(28 "In13.Cu" signal "IN5")
		(30 "In14.Cu" signal "GND6")
		(32 "In15.Cu" signal "IN6")
		(34 "In16.Cu" signal "GND7")
		(2 "B.Cu" signal "BOTTOM")
		(9 "F.Adhes" user "F.Adhesive")
		(11 "B.Adhes" user "B.Adhesive")
		(13 "F.Paste" user "Package Geometry/Pastemask Top")
		(15 "B.Paste" user "Package Geometry/Pastemask Bottom")
		(5 "F.SilkS" user "Ref Des/Silkscreen Top")
		(7 "B.SilkS" user "Ref Des/Silkscreen Bottom")
		(1 "F.Mask" user "Board Geometry/Soldermask Top")
		(3 "B.Mask" user "Board Geometry/Soldermask Bottom")
		(17 "Dwgs.User" user "User.Drawings")
		(19 "Cmts.User" user "User.Comments")
		(21 "Eco1.User" user "User.Eco1")
		(23 "Eco2.User" user "User.Eco2")
		(25 "Edge.Cuts" user "Board Geometry/Outline")
		(27 "Margin" user)
		(31 "F.CrtYd" user "Package Geometry/Place Bound Top")
		(29 "B.CrtYd" user "Package Geometry/Place Bound Bottom")
		(35 "F.Fab" user "Ref Des/Assembly Top")
		(33 "B.Fab" user "Ref Des/Assembly Bottom")
	)
	(footprint ""
		(layer "B.Cu")
		(at 363.550454 -253.43231)
		(property "Reference" "C2532"
			(at 0 0 0)
			(layer "B.SilkS")
			(hide yes)
			(effects
				(font
					(size 1.27 1.27)
				)
				(justify mirror)
			)
		)
		(property "Value" ""
			(at 0 0 0)
			(layer "B.Fab")
			(effects
				(font
					(size 1.27 1.27)
				)
				(justify mirror)
			)
		)
		(duplicate_pad_numbers_are_jumpers no)
		(fp_line
			(start -0.7874 -0.4064)
			(end -0.7874 0.4064)
			(stroke
				(width 0.1524)
				(type default)
			)
			(layer "B.SilkS")
		)
		(fp_line
			(start -0.7874 0.4064)
			(end 0.7874 0.4064)
			(stroke
				(width 0.1524)
				(type default)
			)
			(layer "B.SilkS")
		)
		(fp_line
			(start 0.7874 -0.4064)
			(end -0.7874 -0.4064)
			(stroke
				(width 0.1524)
				(type default)
			)
			(layer "B.SilkS")
		)
		(fp_line
			(start 0.7874 0.4064)
			(end 0.7874 -0.4064)
			(stroke
				(width 0.1524)
				(type default)
			)
			(layer "B.SilkS")
		)
		(fp_line
			(start -0.67945 -0.3048)
			(end -0.67945 0.3048)
			(stroke
				(width 0.1)
				(type default)
			)
			(layer "B.Fab")
		)
		(fp_line
			(start -0.67945 0.3048)
			(end -0.120396 0.3048)
			(stroke
				(width 0.1)
				(type default)
			)
			(layer "B.Fab")
		)
		(fp_line
			(start -0.12065 -0.3048)
			(end -0.67945 -0.3048)
			(stroke
				(width 0.1)
				(type default)
			)
			(layer "B.Fab")
		)
		(fp_line
			(start -0.12065 -0.2794)
			(end -0.12065 -0.3048)
			(stroke
				(width 0.1)
				(type default)
			)
			(layer "B.Fab")
		)
		(fp_line
			(start -0.120396 0.2794)
			(end 0.12065 0.2794)
			(stroke
				(width 0.1)
				(type default)
			)
			(layer "B.Fab")
		)
		(fp_line
			(start -0.120396 0.3048)
			(end -0.120396 0.2794)
			(stroke
				(width 0.1)
				(type default)
			)
			(layer "B.Fab")
		)
		(fp_line
			(start 0.12065 -0.305054)
			(end 0.12065 -0.2794)
			(stroke
				(width 0.1)
				(type default)
			)
			(layer "B.Fab")
		)
		(fp_line
			(start 0.12065 -0.2794)
			(end -0.12065 -0.2794)
			(stroke
				(width 0.1)
				(type default)
			)
			(layer "B.Fab")
		)
		(fp_line
			(start 0.12065 0.2794)
			(end 0.12065 0.3048)
			(stroke
				(width 0.1)
				(type default)
			)
			(layer "B.Fab")
		)
		(fp_line
			(start 0.12065 0.3048)
			(end 0.67945 0.3048)
			(stroke
				(width 0.1)
				(type default)
			)
			(layer "B.Fab")
		)
		(fp_line
			(start 0.67945 -0.305054)
			(end 0.12065 -0.305054)
			(stroke
				(width 0.1)
				(type default)
			)
			(layer "B.Fab")
		)
		(fp_line
			(start 0.67945 0.3048)
			(end 0.67945 -0.305054)
			(stroke
				(width 0.1)
				(type default)
			)
			(layer "B.Fab")
		)
		(pad "1" smd circle
			(at 0.40005 0 180)
			(size 0 0)
			(layers "B.Cu" "B.Mask" "B.Paste")
			(net "PVDDCR_SOC_P0")
		)
		(pad "2" smd circle
			(at -0.40005 0 180)
			(size 0 0)
			(layers "B.Cu" "B.Mask" "B.Paste")
			(net "GND")
		)
	)
	(footprint ""
		(layer "B.Cu")
		(at 164.062918 -121.701814 180)
		(property "Reference" "C1209"
			(at 0 0 0)
			(layer "B.SilkS")
			(hide yes)
			(effects
				(font
					(size 1.27 1.27)
				)
				(justify mirror)
			)
		)
		(property "Value" ""
			(at 0 0 0)
			(layer "B.Fab")
			(effects
				(font
					(size 1.27 1.27)
				)
				(justify mirror)
			)
		)
		(duplicate_pad_numbers_are_jumpers no)
		(fp_line
			(start 0.7874 0.4064)
			(end 0.7874 -0.4064)
			(stroke
				(width 0.1524)
				(type default)
			)
			(layer "B.SilkS")
		)
		(fp_line
			(start 0.7874 -0.4064)
			(end -0.7874 -0.4064)
			(stroke
				(width 0.1524)
				(type default)
			)
			(layer "B.SilkS")
		)
		(fp_line
			(start -0.7874 0.4064)
			(end 0.7874 0.4064)
			(stroke
				(width 0.1524)
				(type default)
			)
			(layer "B.SilkS")
		)
		(fp_line
			(start -0.7874 -0.4064)
			(end -0.7874 0.4064)
			(stroke
				(width 0.1524)
				(type default)
			)
			(layer "B.SilkS")
		)
		(fp_line
			(start 0.67945 0.3048)
			(end 0.67945 -0.305054)
			(stroke
				(width 0.1)
				(type default)
			)
			(layer "B.Fab")
		)
		(fp_line
			(start 0.67945 -0.305054)
			(end 0.12065 -0.305054)
			(stroke
				(width 0.1)
				(type default)
			)
			(layer "B.Fab")
		)
		(fp_line
			(start 0.12065 0.3048)
			(end 0.67945 0.3048)
			(stroke
				(width 0.1)
				(type default)
			)
			(layer "B.Fab")
		)
		(fp_line
			(start 0.12065 0.2794)
			(end 0.12065 0.3048)
			(stroke
				(width 0.1)
				(type default)
			)
			(layer "B.Fab")
		)
		(fp_line
			(start 0.12065 -0.2794)
			(end -0.12065 -0.2794)
			(stroke
				(width 0.1)
				(type default)
			)
			(layer "B.Fab")
		)
		(fp_line
			(start 0.12065 -0.305054)
			(end 0.12065 -0.2794)
			(stroke
				(width 0.1)
				(type default)
			)
			(layer "B.Fab")
		)
		(fp_line
			(start -0.120396 0.3048)
			(end -0.120396 0.2794)
			(stroke
				(width 0.1)
				(type default)
			)
			(layer "B.Fab")
		)
		(fp_line
			(start -0.120396 0.2794)
			(end 0.12065 0.2794)
			(stroke
				(width 0.1)
				(type default)
			)
			(layer "B.Fab")
		)
		(fp_line
			(start -0.12065 -0.2794)
			(end -0.12065 -0.3048)
			(stroke
				(width 0.1)
				(type default)
			)
			(layer "B.Fab")
		)
		(fp_line
			(start -0.12065 -0.3048)
			(end -0.67945 -0.3048)
			(stroke
				(width 0.1)
				(type default)
			)
			(layer "B.Fab")
		)
		(fp_line
			(start -0.67945 0.3048)
			(end -0.120396 0.3048)
			(stroke
				(width 0.1)
				(type default)
			)
			(layer "B.Fab")
		)
		(fp_line
			(start -0.67945 -0.3048)
			(end -0.67945 0.3048)
			(stroke
				(width 0.1)
				(type default)
			)
			(layer "B.Fab")
		)
		(pad "1" smd circle
			(at 0.40005 0)
			(size 0 0)
			(layers "B.Cu" "B.Mask" "B.Paste")
			(net "SCM_SYS_PWROK_R2")
		)
		(pad "2" smd circle
			(at -0.40005 0)
			(size 0 0)
			(layers "B.Cu" "B.Mask" "B.Paste")
			(net "GND")
		)
	)
)
